(kicad_pcb
	(version 20211014)
	(generator pcbnew)
	(general
    (thickness 1.6)
  )
	(paper "A4")
	(title_block
    (title "SA800U (Snapdragon 845) Baseboard")
    (date "2023-10-19")
    (rev "1.0.3")
    (company "Antmicro Ltd.")
    (comment 1 "www.antmicro.com")
		(comment 9 "footprints 283-289 of 589")
	)
	(layers
    (0 "F.Cu" signal)
    (1 "In1.Cu" power)
    (2 "In2.Cu" signal)
    (3 "In3.Cu" signal)
    (4 "In4.Cu" power)
    (31 "B.Cu" signal)
    (32 "B.Adhes" user "B.Adhesive")
    (33 "F.Adhes" user "F.Adhesive")
    (34 "B.Paste" user)
    (35 "F.Paste" user)
    (36 "B.SilkS" user "B.Silkscreen")
    (37 "F.SilkS" user "F.Silkscreen")
    (38 "B.Mask" user)
    (39 "F.Mask" user)
    (40 "Dwgs.User" user "User.Drawings")
    (41 "Cmts.User" user "User.Comments")
    (42 "Eco1.User" user "User.Eco1")
    (43 "Eco2.User" user "User.Eco2")
    (44 "Edge.Cuts" user)
    (45 "Margin" user)
    (46 "B.CrtYd" user "B.Courtyard")
    (47 "F.CrtYd" user "F.Courtyard")
    (48 "B.Fab" user)
    (49 "F.Fab" user)
  )
	(footprint "sa800u-baseboard-hw-footprints:MS621FE-FL11E" (layer "B.Cu")
    (tedit 60B0E4EA)
    (at 99.249 119.299 180)
    (property "Author" "Antmicro")
    (property "License" "Apache-2.0")
    (property "MPN" "MS621FE-FL11E")
    (property "Manufacturer" "Seiko")
    (property "Sheetfile" "som.kicad_sch")
    (property "Sheetname" "SoM")
    (attr smd)
    (fp_text reference "BAT1" (at 1.209 2.409) (layer "B.SilkS")
      (effects (font (size 0.7 0.7) (thickness 0.15)) (justify left bottom mirror))
    )
    (fp_text value "Battery_Holder_MS621FE-FL11E" (at -0.001 -6.2) (layer "B.Fab")
      (effects (font (size 0.7 0.7) (thickness 0.15)) (justify left bottom mirror))
    )
    (fp_text user "COPPER KEEPOUT" (at -0.2 2.45 90 unlocked) (layer "B.Fab")
      (effects (font (size 0.35 0.35) (thickness 0.0875)) (justify left bottom mirror))
    )
    (fp_text user "${REFERENCE}" (at 3.5 8.25) (layer "B.Fab") hide
      (effects (font (size 0.7 0.7) (thickness 0.15)) (justify right bottom mirror))
    )
    (fp_text user "Author: Antmicro" (at 3.5 9.45) (layer "B.Fab") hide
      (effects (font (size 0.7 0.7) (thickness 0.15)) (justify right bottom mirror))
    )
    (fp_text user "License: Apache-2.0" (at 3.5 10.65) (layer "B.Fab") hide
      (effects (font (size 0.7 0.7) (thickness 0.15)) (justify right bottom mirror))
    )
    (fp_arc (start -1.2 2.15) (mid 0 -4.834) (end 1.2 2.15) (layer "B.SilkS") (width 0.15))
    (fp_line (start 1.209 5.038) (end -1.191 5.038) (layer "B.CrtYd") (width 0.05))
    (fp_line (start -1.191 5.038) (end -1.191 2.148) (layer "B.CrtYd") (width 0.05))
    (fp_line (start 1.209 5.038) (end 1.209 2.148) (layer "B.CrtYd") (width 0.05))
    (fp_arc (start -1.191 2.148) (mid 0.009 -4.852014) (end 1.209 2.148) (layer "B.CrtYd") (width 0.05))
    (fp_line (start 1.2 5.049) (end 1.2 2.15) (layer "B.Fab") (width 0.15))
    (fp_line (start -1.2 5.049) (end -1.2 2.15) (layer "B.Fab") (width 0.15))
    (fp_line (start 1.2 5.049) (end -1.2 5.049) (layer "B.Fab") (width 0.15))
    (fp_circle (center -0.001 -1.25) (end -0.001 2.25) (layer "B.Fab") (width 0.15) (fill none))
    (pad "+" smd rect (at -0.751 4.049 270) (size 1.8 0.75) (layers "B.Cu" "B.Paste" "B.Mask")
      (net 336 "/SoM/VRTC") (pinfunction "+") (pintype "passive"))
    (pad "-" smd rect (at 0.749 4.049 270) (size 1.8 0.75) (layers "B.Cu" "B.Paste" "B.Mask")
      (net 1 "GND") (pinfunction "-") (pintype "passive"))
    (zone (net 0) (net_name "") (layers "B.Cu" "B.CrtYd") (hatch edge 0.508)
      (connect_pads (clearance 0))
      (min_thickness 0.254)
      (keepout (tracks allowed) (vias not_allowed) (pads not_allowed) (copperpour not_allowed) (footprints allowed))
      (fill (thermal_gap 0.508) (thermal_bridge_width 0.508))
      (polygon
        (pts
          (xy 100.4 121.8)
          (xy 100.4 116.16)
          (xy 98.1 116.16)
          (xy 98.1 121.8)
        )
      )
    )
  )
	(footprint "sa800u-baseboard-hw-footprints:L_Murata_025020_0605Metric" (layer "B.Cu")
    (tedit 61AA2C4F)
    (at 93.7 93.7 90)
    (property "Author" "Antmicro")
    (property "License" "Apache-2.0")
    (property "MPN" "NFP0QHB242HS2D")
    (property "Manufacturer" "Murata")
    (property "Sheetfile" "camera-interface.kicad_sch")
    (property "Sheetname" "Camera Interface")
    (attr smd)
    (fp_text reference "L17" (at -0.44 0.33 270) (layer "B.SilkS")
      (effects (font (size 0.7 0.7) (thickness 0.15)) (justify left bottom mirror))
    )
    (fp_text value "NFP0QHB242HS2D" (at 0 -1.55 270) (layer "B.Fab")
      (effects (font (size 0.7 0.7) (thickness 0.15)) (justify left bottom mirror))
    )
    (fp_text user "${REFERENCE}" (at -1.027 -3.406 270) (layer "B.Fab") hide
      (effects (font (size 0.7 0.7) (thickness 0.15)) (justify left bottom mirror))
    )
    (fp_text user "Author: Antmicro" (at -1.027 -4.605 270) (layer "B.Fab") hide
      (effects (font (size 0.7 0.7) (thickness 0.15)) (justify left bottom mirror))
    )
    (fp_text user "License: Apache-2.0" (at -1.027 -5.805 270) (layer "B.Fab") hide
      (effects (font (size 0.7 0.7) (thickness 0.15)) (justify left bottom mirror))
    )
    (fp_line (start -0.276 -0.45) (end 0.276 -0.45) (layer "B.SilkS") (width 0.15))
    (fp_line (start 0.276 0.45) (end -0.276 0.45) (layer "B.SilkS") (width 0.15))
    (fp_circle (center -0.5 0.5) (end -0.449 0.5) (layer "B.SilkS") (width 0.15) (fill solid))
    (fp_rect (start -0.5 0.6) (end 0.5 -0.6) (layer "B.CrtYd") (width 0.05) (fill none))
    (fp_line (start 0.275 -0.349) (end 0.275 0.351) (layer "B.Fab") (width 0.15))
    (fp_line (start -0.277 -0.349) (end 0.275 -0.349) (layer "B.Fab") (width 0.15))
    (fp_line (start 0.275 0.351) (end -0.277 0.351) (layer "B.Fab") (width 0.15))
    (fp_line (start -0.277 0.351) (end -0.277 -0.349) (layer "B.Fab") (width 0.15))
    (pad "1" smd rect (at -0.25 0.24 90) (size 0.3 0.23) (layers "B.Cu" "B.Paste" "B.Mask")
      (net 19 "CSI1_LN2_P") (pinfunction "1") (pintype "passive"))
    (pad "2" smd rect (at 0.248 0.24 90) (size 0.3 0.23) (layers "B.Cu" "B.Paste" "B.Mask")
      (net 278 "/Camera Interface/CSI1_LN2_FFC_P") (pinfunction "2") (pintype "passive"))
    (pad "3" smd rect (at 0.248 -0.239 90) (size 0.3 0.23) (layers "B.Cu" "B.Paste" "B.Mask")
      (net 279 "/Camera Interface/CSI1_LN2_FFC_N") (pinfunction "3") (pintype "passive"))
    (pad "4" smd rect (at -0.25 -0.239 90) (size 0.3 0.23) (layers "B.Cu" "B.Paste" "B.Mask")
      (net 20 "CSI1_LN2_N") (pinfunction "4") (pintype "passive"))
  )
	(footprint "sa800u-baseboard-hw-footprints:L_Murata_025020_0605Metric" (layer "B.Cu")
    (tedit 61AA2C4F)
    (at 96.3 93.7 90)
    (property "Author" "Antmicro")
    (property "License" "Apache-2.0")
    (property "MPN" "NFP0QHB242HS2D")
    (property "Manufacturer" "Murata")
    (property "Sheetfile" "camera-interface.kicad_sch")
    (property "Sheetname" "Camera Interface")
    (attr smd)
    (fp_text reference "L19" (at -0.44 0.33 270) (layer "B.SilkS")
      (effects (font (size 0.7 0.7) (thickness 0.15)) (justify left bottom mirror))
    )
    (fp_text value "NFP0QHB242HS2D" (at 0 -1.55 270) (layer "B.Fab")
      (effects (font (size 0.7 0.7) (thickness 0.15)) (justify left bottom mirror))
    )
    (fp_text user "License: Apache-2.0" (at -1.027 -5.805 270) (layer "B.Fab") hide
      (effects (font (size 0.7 0.7) (thickness 0.15)) (justify left bottom mirror))
    )
    (fp_text user "${REFERENCE}" (at -1.027 -3.406 270) (layer "B.Fab") hide
      (effects (font (size 0.7 0.7) (thickness 0.15)) (justify left bottom mirror))
    )
    (fp_text user "Author: Antmicro" (at -1.027 -4.605 270) (layer "B.Fab") hide
      (effects (font (size 0.7 0.7) (thickness 0.15)) (justify left bottom mirror))
    )
    (fp_line (start 0.276 0.45) (end -0.276 0.45) (layer "B.SilkS") (width 0.15))
    (fp_line (start -0.276 -0.45) (end 0.276 -0.45) (layer "B.SilkS") (width 0.15))
    (fp_circle (center -0.5 0.5) (end -0.449 0.5) (layer "B.SilkS") (width 0.15) (fill solid))
    (fp_rect (start -0.5 0.6) (end 0.5 -0.6) (layer "B.CrtYd") (width 0.05) (fill none))
    (fp_line (start 0.275 0.351) (end -0.277 0.351) (layer "B.Fab") (width 0.15))
    (fp_line (start -0.277 0.351) (end -0.277 -0.349) (layer "B.Fab") (width 0.15))
    (fp_line (start 0.275 -0.349) (end 0.275 0.351) (layer "B.Fab") (width 0.15))
    (fp_line (start -0.277 -0.349) (end 0.275 -0.349) (layer "B.Fab") (width 0.15))
    (pad "1" smd rect (at -0.25 0.24 90) (size 0.3 0.23) (layers "B.Cu" "B.Paste" "B.Mask")
      (net 24 "CSI1_LN0_P") (pinfunction "1") (pintype "passive"))
    (pad "2" smd rect (at 0.248 0.24 90) (size 0.3 0.23) (layers "B.Cu" "B.Paste" "B.Mask")
      (net 268 "/Camera Interface/CSI1_LN0_FFC_P") (pinfunction "2") (pintype "passive"))
    (pad "3" smd rect (at 0.248 -0.239 90) (size 0.3 0.23) (layers "B.Cu" "B.Paste" "B.Mask")
      (net 269 "/Camera Interface/CSI1_LN0_FFC_N") (pinfunction "3") (pintype "passive"))
    (pad "4" smd rect (at -0.25 -0.239 90) (size 0.3 0.23) (layers "B.Cu" "B.Paste" "B.Mask")
      (net 23 "CSI1_LN0_N") (pinfunction "4") (pintype "passive"))
  )
	(footprint "sa800u-baseboard-hw-footprints:L_Murata_025020_0605Metric" (layer "B.Cu")
    (tedit 61AA2C4F)
    (at 97.6 93.7 90)
    (property "Author" "Antmicro")
    (property "License" "Apache-2.0")
    (property "MPN" "NFP0QHB242HS2D")
    (property "Manufacturer" "Murata")
    (property "Sheetfile" "camera-interface.kicad_sch")
    (property "Sheetname" "Camera Interface")
    (attr smd)
    (fp_text reference "L20" (at -0.44 0.33 270) (layer "B.SilkS")
      (effects (font (size 0.7 0.7) (thickness 0.15)) (justify left bottom mirror))
    )
    (fp_text value "NFP0QHB242HS2D" (at 0 -1.55 270) (layer "B.Fab")
      (effects (font (size 0.7 0.7) (thickness 0.15)) (justify left bottom mirror))
    )
    (fp_text user "License: Apache-2.0" (at -1.027 -5.805 270) (layer "B.Fab") hide
      (effects (font (size 0.7 0.7) (thickness 0.15)) (justify left bottom mirror))
    )
    (fp_text user "Author: Antmicro" (at -1.027 -4.605 270) (layer "B.Fab") hide
      (effects (font (size 0.7 0.7) (thickness 0.15)) (justify left bottom mirror))
    )
    (fp_text user "${REFERENCE}" (at -1.027 -3.406 270) (layer "B.Fab") hide
      (effects (font (size 0.7 0.7) (thickness 0.15)) (justify left bottom mirror))
    )
    (fp_line (start 0.276 0.45) (end -0.276 0.45) (layer "B.SilkS") (width 0.15))
    (fp_line (start -0.276 -0.45) (end 0.276 -0.45) (layer "B.SilkS") (width 0.15))
    (fp_circle (center -0.5 0.5) (end -0.449 0.5) (layer "B.SilkS") (width 0.15) (fill solid))
    (fp_rect (start -0.5 0.6) (end 0.5 -0.6) (layer "B.CrtYd") (width 0.05) (fill none))
    (fp_line (start -0.277 -0.349) (end 0.275 -0.349) (layer "B.Fab") (width 0.15))
    (fp_line (start 0.275 0.351) (end -0.277 0.351) (layer "B.Fab") (width 0.15))
    (fp_line (start -0.277 0.351) (end -0.277 -0.349) (layer "B.Fab") (width 0.15))
    (fp_line (start 0.275 -0.349) (end 0.275 0.351) (layer "B.Fab") (width 0.15))
    (pad "1" smd rect (at -0.25 0.24 90) (size 0.3 0.23) (layers "B.Cu" "B.Paste" "B.Mask")
      (net 25 "CSI1_CLK_P") (pinfunction "1") (pintype "passive"))
    (pad "2" smd rect (at 0.248 0.24 90) (size 0.3 0.23) (layers "B.Cu" "B.Paste" "B.Mask")
      (net 274 "/Camera Interface/CSI1_CLK_FFC_P") (pinfunction "2") (pintype "passive"))
    (pad "3" smd rect (at 0.248 -0.239 90) (size 0.3 0.23) (layers "B.Cu" "B.Paste" "B.Mask")
      (net 275 "/Camera Interface/CSI1_CLK_FFC_N") (pinfunction "3") (pintype "passive"))
    (pad "4" smd rect (at -0.25 -0.239 90) (size 0.3 0.23) (layers "B.Cu" "B.Paste" "B.Mask")
      (net 26 "CSI1_CLK_N") (pinfunction "4") (pintype "passive"))
  )
	(footprint "sa800u-baseboard-hw-footprints:L_Murata_025020_0605Metric" (layer "B.Cu")
    (tedit 61AA2C4F)
    (at 101.8 93.7 90)
    (property "Author" "Antmicro")
    (property "License" "Apache-2.0")
    (property "MPN" "NFP0QHB242HS2D")
    (property "Manufacturer" "Murata")
    (property "Sheetfile" "camera-interface.kicad_sch")
    (property "Sheetname" "Camera Interface")
    (attr smd)
    (fp_text reference "L21" (at -0.45 0.43 270) (layer "B.SilkS")
      (effects (font (size 0.7 0.7) (thickness 0.15)) (justify left bottom mirror))
    )
    (fp_text value "NFP0QHB242HS2D" (at 0 -1.55 270) (layer "B.Fab")
      (effects (font (size 0.7 0.7) (thickness 0.15)) (justify left bottom mirror))
    )
    (fp_text user "${REFERENCE}" (at -1.027 -3.406 270) (layer "B.Fab") hide
      (effects (font (size 0.7 0.7) (thickness 0.15)) (justify left bottom mirror))
    )
    (fp_text user "License: Apache-2.0" (at -1.027 -5.805 270) (layer "B.Fab") hide
      (effects (font (size 0.7 0.7) (thickness 0.15)) (justify left bottom mirror))
    )
    (fp_text user "Author: Antmicro" (at -1.027 -4.605 270) (layer "B.Fab") hide
      (effects (font (size 0.7 0.7) (thickness 0.15)) (justify left bottom mirror))
    )
    (fp_line (start 0.276 0.45) (end -0.276 0.45) (layer "B.SilkS") (width 0.15))
    (fp_line (start -0.276 -0.45) (end 0.276 -0.45) (layer "B.SilkS") (width 0.15))
    (fp_circle (center -0.5 0.5) (end -0.449 0.5) (layer "B.SilkS") (width 0.15) (fill solid))
    (fp_rect (start -0.5 0.6) (end 0.5 -0.6) (layer "B.CrtYd") (width 0.05) (fill none))
    (fp_line (start 0.275 0.351) (end -0.277 0.351) (layer "B.Fab") (width 0.15))
    (fp_line (start 0.275 -0.349) (end 0.275 0.351) (layer "B.Fab") (width 0.15))
    (fp_line (start -0.277 -0.349) (end 0.275 -0.349) (layer "B.Fab") (width 0.15))
    (fp_line (start -0.277 0.351) (end -0.277 -0.349) (layer "B.Fab") (width 0.15))
    (pad "1" smd rect (at -0.25 0.24 90) (size 0.3 0.23) (layers "B.Cu" "B.Paste" "B.Mask")
      (net 28 "CSI0_LN3_P") (pinfunction "1") (pintype "passive"))
    (pad "2" smd rect (at 0.248 0.24 90) (size 0.3 0.23) (layers "B.Cu" "B.Paste" "B.Mask")
      (net 280 "/Camera Interface/CSI0_LN3_FFC_P") (pinfunction "2") (pintype "passive"))
    (pad "3" smd rect (at 0.248 -0.239 90) (size 0.3 0.23) (layers "B.Cu" "B.Paste" "B.Mask")
      (net 281 "/Camera Interface/CSI0_LN3_FFC_N") (pinfunction "3") (pintype "passive"))
    (pad "4" smd rect (at -0.25 -0.239 90) (size 0.3 0.23) (layers "B.Cu" "B.Paste" "B.Mask")
      (net 27 "CSI0_LN3_N") (pinfunction "4") (pintype "passive"))
  )
	(footprint "sa800u-baseboard-hw-footprints:L_Murata_025020_0605Metric" (layer "B.Cu")
    (tedit 61AA2C4F)
    (at 103.1 93.7 90)
    (property "Author" "Antmicro")
    (property "License" "Apache-2.0")
    (property "MPN" "NFP0QHB242HS2D")
    (property "Manufacturer" "Murata")
    (property "Sheetfile" "camera-interface.kicad_sch")
    (property "Sheetname" "Camera Interface")
    (attr smd)
    (fp_text reference "L22" (at -0.45 0.43 270) (layer "B.SilkS")
      (effects (font (size 0.7 0.7) (thickness 0.15)) (justify left bottom mirror))
    )
    (fp_text value "NFP0QHB242HS2D" (at 0 -1.55 270) (layer "B.Fab")
      (effects (font (size 0.7 0.7) (thickness 0.15)) (justify left bottom mirror))
    )
    (fp_text user "License: Apache-2.0" (at -1.027 -5.805 270) (layer "B.Fab") hide
      (effects (font (size 0.7 0.7) (thickness 0.15)) (justify left bottom mirror))
    )
    (fp_text user "${REFERENCE}" (at -1.027 -3.406 270) (layer "B.Fab") hide
      (effects (font (size 0.7 0.7) (thickness 0.15)) (justify left bottom mirror))
    )
    (fp_text user "Author: Antmicro" (at -1.027 -4.605 270) (layer "B.Fab") hide
      (effects (font (size 0.7 0.7) (thickness 0.15)) (justify left bottom mirror))
    )
    (fp_line (start -0.276 -0.45) (end 0.276 -0.45) (layer "B.SilkS") (width 0.15))
    (fp_line (start 0.276 0.45) (end -0.276 0.45) (layer "B.SilkS") (width 0.15))
    (fp_circle (center -0.5 0.5) (end -0.449 0.5) (layer "B.SilkS") (width 0.15) (fill solid))
    (fp_rect (start -0.5 0.6) (end 0.5 -0.6) (layer "B.CrtYd") (width 0.05) (fill none))
    (fp_line (start 0.275 -0.349) (end 0.275 0.351) (layer "B.Fab") (width 0.15))
    (fp_line (start -0.277 0.351) (end -0.277 -0.349) (layer "B.Fab") (width 0.15))
    (fp_line (start 0.275 0.351) (end -0.277 0.351) (layer "B.Fab") (width 0.15))
    (fp_line (start -0.277 -0.349) (end 0.275 -0.349) (layer "B.Fab") (width 0.15))
    (pad "1" smd rect (at -0.25 0.24 90) (size 0.3 0.23) (layers "B.Cu" "B.Paste" "B.Mask")
      (net 29 "CSI0_LN2_P") (pinfunction "1") (pintype "passive"))
    (pad "2" smd rect (at 0.248 0.24 90) (size 0.3 0.23) (layers "B.Cu" "B.Paste" "B.Mask")
      (net 276 "/Camera Interface/CSI0_LN2_FFC_P") (pinfunction "2") (pintype "passive"))
    (pad "3" smd rect (at 0.248 -0.239 90) (size 0.3 0.23) (layers "B.Cu" "B.Paste" "B.Mask")
      (net 277 "/Camera Interface/CSI0_LN2_FFC_N") (pinfunction "3") (pintype "passive"))
    (pad "4" smd rect (at -0.25 -0.239 90) (size 0.3 0.23) (layers "B.Cu" "B.Paste" "B.Mask")
      (net 30 "CSI0_LN2_N") (pinfunction "4") (pintype "passive"))
  )
	(footprint "sa800u-baseboard-hw-footprints:L_Murata_025020_0605Metric" (layer "B.Cu")
    (tedit 61AA2C4F)
    (at 104.4 93.7 90)
    (property "Author" "Antmicro")
    (property "License" "Apache-2.0")
    (property "MPN" "NFP0QHB242HS2D")
    (property "Manufacturer" "Murata")
    (property "Sheetfile" "camera-interface.kicad_sch")
    (property "Sheetname" "Camera Interface")
    (attr smd)
    (fp_text reference "L23" (at -0.45 0.43 270) (layer "B.SilkS")
      (effects (font (size 0.7 0.7) (thickness 0.15)) (justify left bottom mirror))
    )
    (fp_text value "NFP0QHB242HS2D" (at 0 -1.55 270) (layer "B.Fab")
      (effects (font (size 0.7 0.7) (thickness 0.15)) (justify left bottom mirror))
    )
    (fp_text user "${REFERENCE}" (at -1.027 -3.406 270) (layer "B.Fab") hide
      (effects (font (size 0.7 0.7) (thickness 0.15)) (justify left bottom mirror))
    )
    (fp_text user "License: Apache-2.0" (at -1.027 -5.805 270) (layer "B.Fab") hide
      (effects (font (size 0.7 0.7) (thickness 0.15)) (justify left bottom mirror))
    )
    (fp_text user "Author: Antmicro" (at -1.027 -4.605 270) (layer "B.Fab") hide
      (effects (font (size 0.7 0.7) (thickness 0.15)) (justify left bottom mirror))
    )
    (fp_line (start -0.276 -0.45) (end 0.276 -0.45) (layer "B.SilkS") (width 0.15))
    (fp_line (start 0.276 0.45) (end -0.276 0.45) (layer "B.SilkS") (width 0.15))
    (fp_circle (center -0.5 0.5) (end -0.449 0.5) (layer "B.SilkS") (width 0.15) (fill solid))
    (fp_rect (start -0.5 0.6) (end 0.5 -0.6) (layer "B.CrtYd") (width 0.05) (fill none))
    (fp_line (start 0.275 -0.349) (end 0.275 0.351) (layer "B.Fab") (width 0.15))
    (fp_line (start 0.275 0.351) (end -0.277 0.351) (layer "B.Fab") (width 0.15))
    (fp_line (start -0.277 -0.349) (end 0.275 -0.349) (layer "B.Fab") (width 0.15))
    (fp_line (start -0.277 0.351) (end -0.277 -0.349) (layer "B.Fab") (width 0.15))
    (pad "1" smd rect (at -0.25 0.24 90) (size 0.3 0.23) (layers "B.Cu" "B.Paste" "B.Mask")
      (net 32 "CSI0_LN1_P") (pinfunction "1") (pintype "passive"))
    (pad "2" smd rect (at 0.248 0.24 90) (size 0.3 0.23) (layers "B.Cu" "B.Paste" "B.Mask")
      (net 270 "/Camera Interface/CSI0_LN1_FFC_P") (pinfunction "2") (pintype "passive"))
    (pad "3" smd rect (at 0.248 -0.239 90) (size 0.3 0.23) (layers "B.Cu" "B.Paste" "B.Mask")
      (net 271 "/Camera Interface/CSI0_LN1_FFC_N") (pinfunction "3") (pintype "passive"))
    (pad "4" smd rect (at -0.25 -0.239 90) (size 0.3 0.23) (layers "B.Cu" "B.Paste" "B.Mask")
      (net 31 "CSI0_LN1_N") (pinfunction "4") (pintype "passive"))
  )
)
